# T6G (Grand Teton) — schematic netlist excerpt (pin names and nets, part order shuffled) for the footprints in the layout excerpt that follows; sources: Cadence DE-HDL packaged netlist, KiCad conversion of 04192023_DAF0TMB3IC0_F0TG_MB_C_brd_V02_OCP.brd

R6303  Q_RES  200K 1% EMPTY  pkg 0402LF  page 178 : A = P3V3_AUX ; B = USB_HUB2_MRP_CFG_BC_EN
C1958  Q_CAP  0.1UF 25V 10% X7R  pkg 0402  page 128 : A = P3V3_AUX ; B = GND

(kicad_pcb
	(version 20260206)
	(generator "pcbnew")
	(generator_version "10.0")
	(general
		(thickness 1.6)
		(legacy_teardrops no)
	)
	(paper "A4")
	(title_block
		(title "04192023_DAF0TMB3IC0_F0TG_MB_C_brd_V02_OCP.brd")
		(comment 1 "Grand Teton / footprints 4820-4821 of 8354")
	)
	(layers
		(0 "F.Cu" signal "TOP")
		(4 "In1.Cu" signal "GND")
		(6 "In2.Cu" signal "IN1")
		(8 "In3.Cu" signal "GND1")
		(10 "In4.Cu" signal "IN2")
		(12 "In5.Cu" signal "GND2")
		(14 "In6.Cu" signal "IN3")
		(16 "In7.Cu" signal "GND3")
		(18 "In8.Cu" signal "VCC")
		(20 "In9.Cu" signal "VCC1")
		(22 "In10.Cu" signal "GND4")
		(24 "In11.Cu" signal "IN4")
		(26 "In12.Cu" signal "GND5")
		(28 "In13.Cu" signal "IN5")
		(30 "In14.Cu" signal "GND6")
		(32 "In15.Cu" signal "IN6")
		(34 "In16.Cu" signal "GND7")
		(2 "B.Cu" signal "BOTTOM")
		(9 "F.Adhes" user "F.Adhesive")
		(11 "B.Adhes" user "B.Adhesive")
		(13 "F.Paste" user "Package Geometry/Pastemask Top")
		(15 "B.Paste" user "Package Geometry/Pastemask Bottom")
		(5 "F.SilkS" user "Ref Des/Silkscreen Top")
		(7 "B.SilkS" user "Ref Des/Silkscreen Bottom")
		(1 "F.Mask" user "Board Geometry/Soldermask Top")
		(3 "B.Mask" user "Board Geometry/Soldermask Bottom")
		(17 "Dwgs.User" user "User.Drawings")
		(19 "Cmts.User" user "User.Comments")
		(21 "Eco1.User" user "User.Eco1")
		(23 "Eco2.User" user "User.Eco2")
		(25 "Edge.Cuts" user "Board Geometry/Outline")
		(27 "Margin" user)
		(31 "F.CrtYd" user "Package Geometry/Place Bound Top")
		(29 "B.CrtYd" user "Package Geometry/Place Bound Bottom")
		(35 "F.Fab" user "Ref Des/Assembly Top")
		(33 "B.Fab" user "Ref Des/Assembly Bottom")
	)
	(footprint ""
		(layer "F.Cu")
		(at 113.613946 -54.882034 -90)
		(property "Reference" "R6303"
			(at 0 0 270)
			(layer "F.SilkS")
			(hide yes)
			(effects
				(font
					(size 1.27 1.27)
				)
			)
		)
		(property "Value" ""
			(at 0 0 270)
			(layer "F.Fab")
			(effects
				(font
					(size 1.27 1.27)
				)
			)
		)
		(duplicate_pad_numbers_are_jumpers no)
		(fp_line
			(start -0.7874 0.4064)
			(end -0.7874 -0.4064)
			(stroke
				(width 0.1524)
				(type default)
			)
			(layer "F.SilkS")
		)
		(fp_line
			(start 0.7874 0.4064)
			(end -0.7874 0.4064)
			(stroke
				(width 0.1524)
				(type default)
			)
			(layer "F.SilkS")
		)
		(fp_line
			(start -0.7874 -0.4064)
			(end 0.7874 -0.4064)
			(stroke
				(width 0.1524)
				(type default)
			)
			(layer "F.SilkS")
		)
		(fp_line
			(start 0.7874 -0.4064)
			(end 0.7874 0.4064)
			(stroke
				(width 0.1524)
				(type default)
			)
			(layer "F.SilkS")
		)
		(fp_line
			(start -0.67945 0.3048)
			(end -0.67945 -0.305054)
			(stroke
				(width 0.1)
				(type default)
			)
			(layer "F.Fab")
		)
		(fp_line
			(start -0.12065 0.3048)
			(end -0.67945 0.3048)
			(stroke
				(width 0.1)
				(type default)
			)
			(layer "F.Fab")
		)
		(fp_line
			(start 0.120396 0.3048)
			(end 0.120396 0.2794)
			(stroke
				(width 0.1)
				(type default)
			)
			(layer "F.Fab")
		)
		(fp_line
			(start 0.67945 0.3048)
			(end 0.120396 0.3048)
			(stroke
				(width 0.1)
				(type default)
			)
			(layer "F.Fab")
		)
		(fp_line
			(start -0.12065 0.2794)
			(end -0.12065 0.3048)
			(stroke
				(width 0.1)
				(type default)
			)
			(layer "F.Fab")
		)
		(fp_line
			(start 0.120396 0.2794)
			(end -0.12065 0.2794)
			(stroke
				(width 0.1)
				(type default)
			)
			(layer "F.Fab")
		)
		(fp_line
			(start -0.12065 -0.2794)
			(end 0.12065 -0.2794)
			(stroke
				(width 0.1)
				(type default)
			)
			(layer "F.Fab")
		)
		(fp_line
			(start 0.12065 -0.2794)
			(end 0.12065 -0.3048)
			(stroke
				(width 0.1)
				(type default)
			)
			(layer "F.Fab")
		)
		(fp_line
			(start 0.12065 -0.3048)
			(end 0.67945 -0.3048)
			(stroke
				(width 0.1)
				(type default)
			)
			(layer "F.Fab")
		)
		(fp_line
			(start 0.67945 -0.3048)
			(end 0.67945 0.3048)
			(stroke
				(width 0.1)
				(type default)
			)
			(layer "F.Fab")
		)
		(fp_line
			(start -0.67945 -0.305054)
			(end -0.12065 -0.305054)
			(stroke
				(width 0.1)
				(type default)
			)
			(layer "F.Fab")
		)
		(fp_line
			(start -0.12065 -0.305054)
			(end -0.12065 -0.2794)
			(stroke
				(width 0.1)
				(type default)
			)
			(layer "F.Fab")
		)
		(pad "1" smd circle
			(at -0.40005 0 270)
			(size 0 0)
			(layers "F.Cu" "F.Mask" "F.Paste")
			(net "P3V3_AUX")
		)
		(pad "2" smd circle
			(at 0.40005 0 270)
			(size 0 0)
			(layers "F.Cu" "F.Mask" "F.Paste")
			(net "USB_HUB2_MRP_CFG_BC_EN")
		)
	)
	(footprint ""
		(layer "F.Cu")
		(at 119.761 -426.72)
		(property "Reference" "C1958"
			(at 0 0 0)
			(layer "F.SilkS")
			(hide yes)
			(effects
				(font
					(size 1.27 1.27)
				)
			)
		)
		(property "Value" ""
			(at 0 0 0)
			(layer "F.Fab")
			(effects
				(font
					(size 1.27 1.27)
				)
			)
		)
		(duplicate_pad_numbers_are_jumpers no)
		(fp_line
			(start -0.7874 -0.4064)
			(end 0.7874 -0.4064)
			(stroke
				(width 0.1524)
				(type default)
			)
			(layer "F.SilkS")
		)
		(fp_line
			(start -0.7874 0.4064)
			(end -0.7874 -0.4064)
			(stroke
				(width 0.1524)
				(type default)
			)
			(layer "F.SilkS")
		)
		(fp_line
			(start 0.7874 -0.4064)
			(end 0.7874 0.4064)
			(stroke
				(width 0.1524)
				(type default)
			)
			(layer "F.SilkS")
		)
		(fp_line
			(start 0.7874 0.4064)
			(end -0.7874 0.4064)
			(stroke
				(width 0.1524)
				(type default)
			)
			(layer "F.SilkS")
		)
		(fp_line
			(start -0.67945 -0.305054)
			(end -0.12065 -0.305054)
			(stroke
				(width 0.1)
				(type default)
			)
			(layer "F.Fab")
		)
		(fp_line
			(start -0.67945 0.3048)
			(end -0.67945 -0.305054)
			(stroke
				(width 0.1)
				(type default)
			)
			(layer "F.Fab")
		)
		(fp_line
			(start -0.12065 -0.305054)
			(end -0.12065 -0.2794)
			(stroke
				(width 0.1)
				(type default)
			)
			(layer "F.Fab")
		)
		(fp_line
			(start -0.12065 -0.2794)
			(end 0.12065 -0.2794)
			(stroke
				(width 0.1)
				(type default)
			)
			(layer "F.Fab")
		)
		(fp_line
			(start -0.12065 0.2794)
			(end -0.12065 0.3048)
			(stroke
				(width 0.1)
				(type default)
			)
			(layer "F.Fab")
		)
		(fp_line
			(start -0.12065 0.3048)
			(end -0.67945 0.3048)
			(stroke
				(width 0.1)
				(type default)
			)
			(layer "F.Fab")
		)
		(fp_line
			(start 0.120396 0.2794)
			(end -0.12065 0.2794)
			(stroke
				(width 0.1)
				(type default)
			)
			(layer "F.Fab")
		)
		(fp_line
			(start 0.120396 0.3048)
			(end 0.120396 0.2794)
			(stroke
				(width 0.1)
				(type default)
			)
			(layer "F.Fab")
		)
		(fp_line
			(start 0.12065 -0.3048)
			(end 0.67945 -0.3048)
			(stroke
				(width 0.1)
				(type default)
			)
			(layer "F.Fab")
		)
		(fp_line
			(start 0.12065 -0.2794)
			(end 0.12065 -0.3048)
			(stroke
				(width 0.1)
				(type default)
			)
			(layer "F.Fab")
		)
		(fp_line
			(start 0.67945 -0.3048)
			(end 0.67945 0.3048)
			(stroke
				(width 0.1)
				(type default)
			)
			(layer "F.Fab")
		)
		(fp_line
			(start 0.67945 0.3048)
			(end 0.120396 0.3048)
			(stroke
				(width 0.1)
				(type default)
			)
			(layer "F.Fab")
		)
		(pad "1" smd circle
			(at -0.40005 0)
			(size 0 0)
			(layers "F.Cu" "F.Mask" "F.Paste")
			(net "P3V3_AUX")
		)
		(pad "2" smd circle
			(at 0.40005 0)
			(size 0 0)
			(layers "F.Cu" "F.Mask" "F.Paste")
			(net "GND")
		)
	)
)
